# BASEBOARD_FAB2 (Tioga Pass) — schematic netlist excerpt (pin names and nets, part order shuffled) for the footprints in the layout excerpt that follows; sources: Cadence DE-HDL packaged netlist, KiCad conversion of Wiwynn_Tioga_Pass_MB.brd

EU4D2  NB3W1200L  IC  pkg LCC  page 102
  VDDA  = P3V3_DB1200_A
  GNDA  = GND
  NC(0)  = NC
  \100m_133m_n\  = FM_100M_N
  HBW_BYPASS_LOBW_N  = FM_HBW_BYPASS_LOWBW_N
  PWRGD_PWRDN_N  = FM_DB1200_PWRGD_R
  GND(0)  = GND
  VDDR  = P3V3_DB1200_R
  CLK_INP  = CLK_100M_DB1200_DP
  CLK_INN  = CLK_100M_DB1200_DN
  SA_0  = FM_DB1200_SMB_SA0
  SDA  = SMB_HOST_STBY_LVC3_SDA_R2
  SCL  = SMB_HOST_STBY_LVC3_SCL_R2
  SA_1  = FM_DB1200_SMB_SA1
  NC(2)  = NC
  NC(1)  = NC
  DIF_0P  = CLK_100M_CPU0_BCLK0_R_DP
  DIF_0N  = CLK_100M_CPU0_BCLK0_R_DN
  OE_0_N  = FM_DB1200ZL_BCLKS_EN_N
  OE_1_N  = FM_DB1200ZL_BCLKS_EN_N
  DIF_1P  = CLK_100M_CPU0_BCLK1_R_DP
  DIF_1N  = CLK_100M_CPU0_BCLK1_R_DN
  GND(1)  = GND
  VDD(0)  = P3V3_DB1200
  VDDIO(0)  = P3V3_DB1200
  DIF_2P  = CLK_100M_CPU0_BCLK2_R_DP
  DIF_2N  = CLK_100M_CPU0_BCLK2_R_DN
  OE_2_N  = FM_DB1200ZL_BCLKS_EN_N
  OE_3_N  = FM_CPU0_MCP_CLK_EN_N
  DIF_3P  = CLK_100M_CPU0_PE_REFCLK_R_DP
  DIF_3N  = CLK_100M_CPU0_PE_REFCLK_R_DN
  VDDIO(1)  = P3V3_DB1200
  GND(2)  = GND
  DIF_4P  = CLK_100M_CPU0_RC_REFCLK0_R_DP
  DIF_4N  = CLK_100M_CPU0_RC_REFCLK0_R_DN
  OE_4_N  = FM_CPU0_MCP_CLK_EN_N
  OE_5_N  = FM_CPU0_MCP_CLK_EN_N
  DIF_5P  = CLK_100M_CPU0_RC_REFCLK1_R_DP
  DIF_5N  = CLK_100M_CPU0_RC_REFCLK1_R_DN
  VDD(1)  = P3V3_DB1200
  GND(3)  = GND
  DIF_6P  = CLK_100M_CPU1_BCLK0_R_DP
  DIF_6N  = CLK_100M_CPU1_BCLK0_R_DN
  OE_6_N  = FM_DB1200ZL_BCLKS_EN_N
  OE_7_N  = FM_DB1200ZL_BCLKS_EN_N
  DIF_7P  = CLK_100M_CPU1_BCLK1_R_DP
  DIF_7N  = CLK_100M_CPU1_BCLK1_R_DN
  GND(4)  = GND
  VDDIO(2)  = P3V3_DB1200
  DIF_8P  = CLK_100M_CPU1_BCLK2_R_DP
  DIF_8N  = CLK_100M_CPU1_BCLK2_R_DN
  OE_8_N  = FM_DB1200ZL_BCLKS_EN_N
  OE_9_N  = FM_CPU1_MCP_CLK_EN_N
  DIF_9P  = CLK_100M_CPU1_PE_REFCLK_R_DP
  DIF_9N  = CLK_100M_CPU1_PE_REFCLK_R_DN
  VDDIO(3)  = P3V3_DB1200
  VDD(2)  = P3V3_DB1200
  GND(5)  = GND
  DIF_10P  = CLK_100M_CPU1_RC_REFCLK0_R_DP
  DIF_10N  = CLK_100M_CPU1_RC_REFCLK0_R_DN
  OE_10_N  = FM_CPU1_MCP_CLK_EN_N
  OE_11_N  = FM_CPU1_MCP_CLK_EN_N
  DIF_11P  = CLK_100M_CPU1_RC_REFCLK1_R_DP
  DIF_11N  = CLK_100M_CPU1_RC_REFCLK1_R_DN
  THPAD  = GND

(kicad_pcb
	(version 20260206)
	(generator "pcbnew")
	(generator_version "10.0")
	(general
		(thickness 1.6)
		(legacy_teardrops no)
	)
	(paper "A4")
	(title_block
		(title "Wiwynn_Tioga_Pass_MB.brd")
		(comment 1 "Tioga Pass / footprint 752 of 4770 (EU4D2), pads 18-34 of 65")
	)
	(layers
		(0 "F.Cu" signal "TOP")
		(4 "In1.Cu" signal "L2GND")
		(6 "In2.Cu" signal "L3")
		(8 "In3.Cu" signal "L4GND")
		(10 "In4.Cu" signal "L5")
		(12 "In5.Cu" signal "L6GND")
		(14 "In6.Cu" signal "L7VCC")
		(16 "In7.Cu" signal "L8VCC")
		(18 "In8.Cu" signal "L9GND")
		(20 "In9.Cu" signal "L10")
		(22 "In10.Cu" signal "L11GND")
		(24 "In11.Cu" signal "L12")
		(26 "In12.Cu" signal "L13GND")
		(2 "B.Cu" signal "BOTTOM")
		(9 "F.Adhes" user "F.Adhesive")
		(11 "B.Adhes" user "B.Adhesive")
		(13 "F.Paste" user "Package Geometry/Pastemask Top")
		(15 "B.Paste" user "Package Geometry/Pastemask Bottom")
		(5 "F.SilkS" user "Ref Des/Silkscreen Top")
		(7 "B.SilkS" user "Ref Des/Silkscreen Bottom")
		(1 "F.Mask" user "Board Geometry/Soldermask Top")
		(3 "B.Mask" user "Board Geometry/Soldermask Bottom")
		(17 "Dwgs.User" user "User.Drawings")
		(19 "Cmts.User" user "User.Comments")
		(21 "Eco1.User" user "User.Eco1")
		(23 "Eco2.User" user "User.Eco2")
		(25 "Edge.Cuts" user "Board Geometry/Outline")
		(27 "Margin" user)
		(31 "F.CrtYd" user "Package Geometry/Place Bound Top")
		(29 "B.CrtYd" user "Package Geometry/Place Bound Bottom")
		(35 "F.Fab" user "Ref Des/Assembly Top")
		(33 "B.Fab" user "Ref Des/Assembly Bottom")
	)
	(footprint ""
		(layer "F.Cu")
		(at 169.422826 -80.961992 90)
		(property "Reference" "EU4D2"
			(at -8.471662 1.773174 0)
			(unlocked yes)
			(layer "F.SilkS")
			(effects
				(font
					(size 0.7874 0.5842)
					(thickness 0.1524)
				)
				(justify left)
			)
		)
		(property "Value" ""
			(at 0 0 90)
			(layer "F.Fab")
			(effects
				(font
					(size 1.27 1.27)
				)
			)
		)
		(duplicate_pad_numbers_are_jumpers no)
		(pad "18" smd custom
			(at -3.250692 4.3688 90)
			(size 0.0762 0.0762)
			(layers "F.Cu" "F.Mask" "F.Paste")
			(net "CLK_100M_CPU0_BCLK0_R_DN")
			(options
				(clearance outline)
				(anchor circle)
			)
			(primitives
				(gr_poly
					(pts
						(xy -0.1524 0.381)
						(arc
							(start -0.1524 -0.2286)
							(mid 0 -0.381)
							(end 0.1524 -0.2286)
						)
						(xy 0.1524 0.381)
					)
					(width 0)
					(fill yes)
				)
			)
		)
		(pad "19" smd custom
			(at -2.750566 4.3688 90)
			(size 0.0762 0.0762)
			(layers "F.Cu" "F.Mask" "F.Paste")
			(net "FM_DB1200ZL_BCLKS_EN_N")
			(options
				(clearance outline)
				(anchor circle)
			)
			(primitives
				(gr_poly
					(pts
						(xy -0.1524 0.381)
						(arc
							(start -0.1524 -0.2286)
							(mid 0 -0.381)
							(end 0.1524 -0.2286)
						)
						(xy 0.1524 0.381)
					)
					(width 0)
					(fill yes)
				)
			)
		)
		(pad "20" smd custom
			(at -2.25044 4.3688 90)
			(size 0.0762 0.0762)
			(layers "F.Cu" "F.Mask" "F.Paste")
			(net "FM_DB1200ZL_BCLKS_EN_N")
			(options
				(clearance outline)
				(anchor circle)
			)
			(primitives
				(gr_poly
					(pts
						(xy -0.1524 0.381)
						(arc
							(start -0.1524 -0.2286)
							(mid 0 -0.381)
							(end 0.1524 -0.2286)
						)
						(xy 0.1524 0.381)
					)
					(width 0)
					(fill yes)
				)
			)
		)
		(pad "21" smd custom
			(at -1.750314 4.3688 90)
			(size 0.0762 0.0762)
			(layers "F.Cu" "F.Mask" "F.Paste")
			(net "CLK_100M_CPU0_BCLK1_R_DP")
			(options
				(clearance outline)
				(anchor circle)
			)
			(primitives
				(gr_poly
					(pts
						(xy -0.1524 0.381)
						(arc
							(start -0.1524 -0.2286)
							(mid 0 -0.381)
							(end 0.1524 -0.2286)
						)
						(xy 0.1524 0.381)
					)
					(width 0)
					(fill yes)
				)
			)
		)
		(pad "22" smd custom
			(at -1.250188 4.3688 90)
			(size 0.0762 0.0762)
			(layers "F.Cu" "F.Mask" "F.Paste")
			(net "CLK_100M_CPU0_BCLK1_R_DN")
			(options
				(clearance outline)
				(anchor circle)
			)
			(primitives
				(gr_poly
					(pts
						(xy -0.1524 0.381)
						(arc
							(start -0.1524 -0.2286)
							(mid 0 -0.381)
							(end 0.1524 -0.2286)
						)
						(xy 0.1524 0.381)
					)
					(width 0)
					(fill yes)
				)
			)
		)
		(pad "23" smd custom
			(at -0.750062 4.3688 90)
			(size 0.0762 0.0762)
			(layers "F.Cu" "F.Mask" "F.Paste")
			(net "GND")
			(options
				(clearance outline)
				(anchor circle)
			)
			(primitives
				(gr_poly
					(pts
						(xy -0.1524 0.381)
						(arc
							(start -0.1524 -0.2286)
							(mid 0 -0.381)
							(end 0.1524 -0.2286)
						)
						(xy 0.1524 0.381)
					)
					(width 0)
					(fill yes)
				)
			)
		)
		(pad "24" smd custom
			(at -0.249936 4.3688 90)
			(size 0.0762 0.0762)
			(layers "F.Cu" "F.Mask" "F.Paste")
			(net "P3V3_DB1200")
			(options
				(clearance outline)
				(anchor circle)
			)
			(primitives
				(gr_poly
					(pts
						(xy -0.1524 0.381)
						(arc
							(start -0.1524 -0.2286)
							(mid 0 -0.381)
							(end 0.1524 -0.2286)
						)
						(xy 0.1524 0.381)
					)
					(width 0)
					(fill yes)
				)
			)
		)
		(pad "25" smd custom
			(at 0.25019 4.3688 90)
			(size 0.0762 0.0762)
			(layers "F.Cu" "F.Mask" "F.Paste")
			(net "P3V3_DB1200")
			(options
				(clearance outline)
				(anchor circle)
			)
			(primitives
				(gr_poly
					(pts
						(xy -0.1524 0.381)
						(arc
							(start -0.1524 -0.2286)
							(mid 0 -0.381)
							(end 0.1524 -0.2286)
						)
						(xy 0.1524 0.381)
					)
					(width 0)
					(fill yes)
				)
			)
		)
		(pad "26" smd custom
			(at 0.750316 4.3688 90)
			(size 0.0762 0.0762)
			(layers "F.Cu" "F.Mask" "F.Paste")
			(net "CLK_100M_CPU0_BCLK2_R_DP")
			(options
				(clearance outline)
				(anchor circle)
			)
			(primitives
				(gr_poly
					(pts
						(xy -0.1524 0.381)
						(arc
							(start -0.1524 -0.2286)
							(mid 0 -0.381)
							(end 0.1524 -0.2286)
						)
						(xy 0.1524 0.381)
					)
					(width 0)
					(fill yes)
				)
			)
		)
		(pad "27" smd custom
			(at 1.250442 4.3688 90)
			(size 0.0762 0.0762)
			(layers "F.Cu" "F.Mask" "F.Paste")
			(net "CLK_100M_CPU0_BCLK2_R_DN")
			(options
				(clearance outline)
				(anchor circle)
			)
			(primitives
				(gr_poly
					(pts
						(xy -0.1524 0.381)
						(arc
							(start -0.1524 -0.2286)
							(mid 0 -0.381)
							(end 0.1524 -0.2286)
						)
						(xy 0.1524 0.381)
					)
					(width 0)
					(fill yes)
				)
			)
		)
		(pad "28" smd custom
			(at 1.750568 4.3688 90)
			(size 0.0762 0.0762)
			(layers "F.Cu" "F.Mask" "F.Paste")
			(net "FM_DB1200ZL_BCLKS_EN_N")
			(options
				(clearance outline)
				(anchor circle)
			)
			(primitives
				(gr_poly
					(pts
						(xy -0.1524 0.381)
						(arc
							(start -0.1524 -0.2286)
							(mid 0 -0.381)
							(end 0.1524 -0.2286)
						)
						(xy 0.1524 0.381)
					)
					(width 0)
					(fill yes)
				)
			)
		)
		(pad "29" smd custom
			(at 2.250694 4.3688 90)
			(size 0.0762 0.0762)
			(layers "F.Cu" "F.Mask" "F.Paste")
			(net "FM_CPU0_MCP_CLK_EN_N")
			(options
				(clearance outline)
				(anchor circle)
			)
			(primitives
				(gr_poly
					(pts
						(xy -0.1524 0.381)
						(arc
							(start -0.1524 -0.2286)
							(mid 0 -0.381)
							(end 0.1524 -0.2286)
						)
						(xy 0.1524 0.381)
					)
					(width 0)
					(fill yes)
				)
			)
		)
		(pad "30" smd custom
			(at 2.75082 4.3688 90)
			(size 0.0762 0.0762)
			(layers "F.Cu" "F.Mask" "F.Paste")
			(net "CLK_100M_CPU0_PE_REFCLK_R_DP")
			(options
				(clearance outline)
				(anchor circle)
			)
			(primitives
				(gr_poly
					(pts
						(xy -0.1524 0.381)
						(arc
							(start -0.1524 -0.2286)
							(mid 0 -0.381)
							(end 0.1524 -0.2286)
						)
						(xy 0.1524 0.381)
					)
					(width 0)
					(fill yes)
				)
			)
		)
		(pad "31" smd custom
			(at 3.250946 4.3688 90)
			(size 0.0762 0.0762)
			(layers "F.Cu" "F.Mask" "F.Paste")
			(net "CLK_100M_CPU0_PE_REFCLK_R_DN")
			(options
				(clearance outline)
				(anchor circle)
			)
			(primitives
				(gr_poly
					(pts
						(xy -0.1524 0.381)
						(arc
							(start -0.1524 -0.2286)
							(mid 0 -0.381)
							(end 0.1524 -0.2286)
						)
						(xy 0.1524 0.381)
					)
					(width 0)
					(fill yes)
				)
			)
		)
		(pad "32" smd custom
			(at 3.751072 4.3688 90)
			(size 0.0762 0.0762)
			(layers "F.Cu" "F.Mask" "F.Paste")
			(net "P3V3_DB1200")
			(options
				(clearance outline)
				(anchor circle)
			)
			(primitives
				(gr_poly
					(pts
						(xy -0.1524 0.381)
						(arc
							(start -0.1524 -0.2286)
							(mid 0 -0.381)
							(end 0.1524 -0.2286)
						)
						(xy 0.1524 0.381)
					)
					(width 0)
					(fill yes)
				)
			)
		)
		(pad "33" smd custom
			(at 4.3688 3.751072 90)
			(size 0.0762 0.0762)
			(layers "F.Cu" "F.Mask" "F.Paste")
			(net "GND")
			(options
				(clearance outline)
				(anchor circle)
			)
			(primitives
				(gr_poly
					(pts
						(xy 0.381 0.1524)
						(arc
							(start -0.2286 0.1524)
							(mid -0.381 0)
							(end -0.2286 -0.1524)
						)
						(xy 0.381 -0.1524)
					)
					(width 0)
					(fill yes)
				)
			)
		)
		(pad "34" smd custom
			(at 4.3688 3.250946 90)
			(size 0.0762 0.0762)
			(layers "F.Cu" "F.Mask" "F.Paste")
			(net "CLK_100M_CPU0_RC_REFCLK0_R_DP")
			(options
				(clearance outline)
				(anchor circle)
			)
			(primitives
				(gr_poly
					(pts
						(xy 0.381 0.1524)
						(arc
							(start -0.2286 0.1524)
							(mid -0.381 0)
							(end -0.2286 -0.1524)
						)
						(xy 0.381 -0.1524)
					)
					(width 0)
					(fill yes)
				)
			)
		)
	)
)
